# T6G (Grand Teton) — schematic netlist excerpt (pin names and nets, part order shuffled) for the footprints in the layout excerpt that follows; sources: Cadence DE-HDL packaged netlist, KiCad conversion of 04192023_DAF0TMB3IC0_F0TG_MB_C_brd_V02_OCP.brd

PU297  MP5991GLUZ  MP5991GLU-Z IC  pkg LGA32_TH_0-5_5X5  page 264
  VOUT1  = P12V_AUX
  VOUT2  = P12V_AUX
  D_OC  = HSC_D_OC_4
  \on\  = HSC_ON
  GOK  = HSC_FAULT
  FLT_TYPE  = HSC_FLT_TYPE_4
  NC1  = HSC_NC1_4
  MODE  = HSC_MODE_4
  VIN1  = P12V_PSU
  VIN2  = P12V_PSU
  VIN3  = P12V_PSU
  VIN4  = P12V_PSU
  VIN5  = P12V_PSU
  VIN6  = P12V_PSU
  VIN7  = P12V_PSU
  VIN8  = P12V_PSU
  SCREF_OCWREF  = HSC_SCREF_4
  VTEMP  = HSC_VTEMP
  SS  = HSC_SS
  GND  = AGND_HSC
  VDD33  = HSC_VDD_R_4
  IMON  = HSC_IMON
  CS  = HSC_CS_4
  OCREF  = HSC_OCREF
  VOUT3  = P12V_AUX
  VOUT4  = P12V_AUX
  VOUT5  = P12V_AUX
  VOUT6  = P12V_AUX
  VOUT7  = P12V_AUX
  VOUT8  = P12V_AUX
  VOUT9  = P12V_AUX
  VOUT10  = P12V_AUX
  VIN9  = P12V_PSU

(kicad_pcb
	(version 20260206)
	(generator "pcbnew")
	(generator_version "10.0")
	(general
		(thickness 1.6)
		(legacy_teardrops no)
	)
	(paper "A4")
	(title_block
		(title "04192023_DAF0TMB3IC0_F0TG_MB_C_brd_V02_OCP.brd")
		(comment 1 "Grand Teton / footprints 2685-2685 of 8354")
	)
	(layers
		(0 "F.Cu" signal "TOP")
		(4 "In1.Cu" signal "GND")
		(6 "In2.Cu" signal "IN1")
		(8 "In3.Cu" signal "GND1")
		(10 "In4.Cu" signal "IN2")
		(12 "In5.Cu" signal "GND2")
		(14 "In6.Cu" signal "IN3")
		(16 "In7.Cu" signal "GND3")
		(18 "In8.Cu" signal "VCC")
		(20 "In9.Cu" signal "VCC1")
		(22 "In10.Cu" signal "GND4")
		(24 "In11.Cu" signal "IN4")
		(26 "In12.Cu" signal "GND5")
		(28 "In13.Cu" signal "IN5")
		(30 "In14.Cu" signal "GND6")
		(32 "In15.Cu" signal "IN6")
		(34 "In16.Cu" signal "GND7")
		(2 "B.Cu" signal "BOTTOM")
		(9 "F.Adhes" user "F.Adhesive")
		(11 "B.Adhes" user "B.Adhesive")
		(13 "F.Paste" user "Package Geometry/Pastemask Top")
		(15 "B.Paste" user "Package Geometry/Pastemask Bottom")
		(5 "F.SilkS" user "Ref Des/Silkscreen Top")
		(7 "B.SilkS" user "Ref Des/Silkscreen Bottom")
		(1 "F.Mask" user "Board Geometry/Soldermask Top")
		(3 "B.Mask" user "Board Geometry/Soldermask Bottom")
		(17 "Dwgs.User" user "User.Drawings")
		(19 "Cmts.User" user "User.Comments")
		(21 "Eco1.User" user "User.Eco1")
		(23 "Eco2.User" user "User.Eco2")
		(25 "Edge.Cuts" user "Board Geometry/Outline")
		(27 "Margin" user)
		(31 "F.CrtYd" user "Package Geometry/Place Bound Top")
		(29 "B.CrtYd" user "Package Geometry/Place Bound Bottom")
		(35 "F.Fab" user "Ref Des/Assembly Top")
		(33 "B.Fab" user "Ref Des/Assembly Bottom")
	)
	(footprint ""
		(layer "F.Cu")
		(at 231.540558 -401.920202 180)
		(property "Reference" "PU297"
			(at 2.622804 -5.10286 90)
			(unlocked yes)
			(layer "F.SilkS")
			(effects
				(font
					(size 0.7874 0.5842)
					(thickness 0.1524)
				)
			)
		)
		(property "Value" ""
			(at 0 0 180)
			(layer "F.Fab")
			(effects
				(font
					(size 1.27 1.27)
				)
			)
		)
		(duplicate_pad_numbers_are_jumpers no)
		(fp_line
			(start 2.567686 2.567686)
			(end 2.567686 -2.567686)
			(stroke
				(width 0.1524)
				(type default)
			)
			(layer "F.SilkS")
		)
		(fp_line
			(start 2.567686 -2.567686)
			(end -2.567686 -2.567686)
			(stroke
				(width 0.1524)
				(type default)
			)
			(layer "F.SilkS")
		)
		(fp_line
			(start -2.567686 2.567686)
			(end 2.567686 2.567686)
			(stroke
				(width 0.1524)
				(type default)
			)
			(layer "F.SilkS")
		)
		(fp_line
			(start -2.567686 -2.567686)
			(end -2.567686 2.567686)
			(stroke
				(width 0.1524)
				(type default)
			)
			(layer "F.SilkS")
		)
		(fp_poly
			(pts
				(xy -2.632456 -2.13233) (xy -3.709924 -2.491486) (xy -2.991612 -3.209798)
			)
			(stroke
				(width 0)
				(type default)
			)
			(fill yes)
			(layer "F.SilkS")
		)
		(fp_line
			(start 2.549906 2.549906)
			(end 2.549906 -2.549906)
			(stroke
				(width 0.1)
				(type default)
			)
			(layer "F.Fab")
		)
		(fp_line
			(start 2.549906 -2.549906)
			(end -2.549906 -2.549906)
			(stroke
				(width 0.1)
				(type default)
			)
			(layer "F.Fab")
		)
		(fp_line
			(start -2.549906 2.549906)
			(end 2.549906 2.549906)
			(stroke
				(width 0.1)
				(type default)
			)
			(layer "F.Fab")
		)
		(fp_line
			(start -2.549906 -2.549906)
			(end -2.549906 2.549906)
			(stroke
				(width 0.1)
				(type default)
			)
			(layer "F.Fab")
		)
		(fp_poly
			(pts
				(xy -3.806698 -2.25806) (xy -3.806698 -1.24206) (xy -2.790698 -1.75006)
			)
			(stroke
				(width 0)
				(type default)
			)
			(fill yes)
			(layer "F.Fab")
		)
		(pad "1" smd rect
			(at -2.250186 -1.75006 270)
			(size 0.254 0.3556)
			(layers "F.Cu" "F.Mask" "F.Paste")
			(net "P12V_AUX")
		)
		(pad "2" smd rect
			(at -2.237486 -1.249934 270)
			(size 0.254 0.381)
			(layers "F.Cu" "F.Mask" "F.Paste")
			(net "P12V_AUX")
		)
		(pad "3" smd rect
			(at -2.237486 -0.750062 270)
			(size 0.254 0.381)
			(layers "F.Cu" "F.Mask" "F.Paste")
			(net "HSC_D_OC_4")
		)
		(pad "4" smd rect
			(at -2.237486 -0.249936 270)
			(size 0.254 0.381)
			(layers "F.Cu" "F.Mask" "F.Paste")
			(net "HSC_ON")
		)
		(pad "5" smd rect
			(at -2.237486 0.249936 270)
			(size 0.254 0.381)
			(layers "F.Cu" "F.Mask" "F.Paste")
			(net "HSC_FAULT")
		)
		(pad "6" smd rect
			(at -2.237486 0.750062 270)
			(size 0.254 0.381)
			(layers "F.Cu" "F.Mask" "F.Paste")
			(net "HSC_FLT_TYPE_4")
		)
		(pad "7" smd rect
			(at -2.237486 1.249934 270)
			(size 0.254 0.381)
			(layers "F.Cu" "F.Mask" "F.Paste")
			(net "HSC_NC1_4")
		)
		(pad "8" smd rect
			(at -2.250186 1.75006 270)
			(size 0.254 0.3556)
			(layers "F.Cu" "F.Mask" "F.Paste")
			(net "HSC_MODE_4")
		)
		(pad "9" smd rect
			(at -1.75006 2.250186 180)
			(size 0.254 0.3556)
			(layers "F.Cu" "F.Mask" "F.Paste")
			(net "P12V_PSU")
		)
		(pad "10" smd rect
			(at -1.249934 2.237486 180)
			(size 0.254 0.381)
			(layers "F.Cu" "F.Mask" "F.Paste")
			(net "P12V_PSU")
		)
		(pad "11" smd rect
			(at -0.750062 2.237486 180)
			(size 0.254 0.381)
			(layers "F.Cu" "F.Mask" "F.Paste")
			(net "P12V_PSU")
		)
		(pad "12" smd rect
			(at -0.249936 2.237486 180)
			(size 0.254 0.381)
			(layers "F.Cu" "F.Mask" "F.Paste")
			(net "P12V_PSU")
		)
		(pad "13" smd rect
			(at 0.249936 2.237486 180)
			(size 0.254 0.381)
			(layers "F.Cu" "F.Mask" "F.Paste")
			(net "P12V_PSU")
		)
		(pad "14" smd rect
			(at 0.750062 2.237486 180)
			(size 0.254 0.381)
			(layers "F.Cu" "F.Mask" "F.Paste")
			(net "P12V_PSU")
		)
		(pad "15" smd rect
			(at 1.249934 2.237486 180)
			(size 0.254 0.381)
			(layers "F.Cu" "F.Mask" "F.Paste")
			(net "P12V_PSU")
		)
		(pad "16" smd rect
			(at 1.75006 2.250186 180)
			(size 0.254 0.3556)
			(layers "F.Cu" "F.Mask" "F.Paste")
			(net "P12V_PSU")
		)
		(pad "17" smd rect
			(at 2.250186 1.75006 270)
			(size 0.254 0.3556)
			(layers "F.Cu" "F.Mask" "F.Paste")
			(net "HSC_SCREF_4")
		)
		(pad "18" smd rect
			(at 2.237486 1.249934 270)
			(size 0.254 0.381)
			(layers "F.Cu" "F.Mask" "F.Paste")
			(net "HSC_VTEMP")
		)
		(pad "19" smd rect
			(at 2.237486 0.750062 270)
			(size 0.254 0.381)
			(layers "F.Cu" "F.Mask" "F.Paste")
			(net "HSC_SS")
		)
		(pad "20" smd rect
			(at 2.237486 0.249936 270)
			(size 0.254 0.381)
			(layers "F.Cu" "F.Mask" "F.Paste")
			(net "AGND_HSC")
		)
		(pad "21" smd rect
			(at 2.237486 -0.249936 270)
			(size 0.254 0.381)
			(layers "F.Cu" "F.Mask" "F.Paste")
			(net "HSC_VDD_R_4")
		)
		(pad "22" smd rect
			(at 2.237486 -0.750062 270)
			(size 0.254 0.381)
			(layers "F.Cu" "F.Mask" "F.Paste")
			(net "HSC_IMON")
		)
		(pad "23" smd rect
			(at 2.237486 -1.249934 270)
			(size 0.254 0.381)
			(layers "F.Cu" "F.Mask" "F.Paste")
			(net "HSC_CS_4")
		)
		(pad "24" smd rect
			(at 2.250186 -1.75006 270)
			(size 0.254 0.3556)
			(layers "F.Cu" "F.Mask" "F.Paste")
			(net "HSC_OCREF")
		)
		(pad "25" smd rect
			(at 1.75006 -2.250186 180)
			(size 0.254 0.3556)
			(layers "F.Cu" "F.Mask" "F.Paste")
			(net "P12V_AUX")
		)
		(pad "26" smd rect
			(at 1.249934 -2.237486 180)
			(size 0.254 0.381)
			(layers "F.Cu" "F.Mask" "F.Paste")
			(net "P12V_AUX")
		)
		(pad "27" smd rect
			(at 0.750062 -2.237486 180)
			(size 0.254 0.381)
			(layers "F.Cu" "F.Mask" "F.Paste")
			(net "P12V_AUX")
		)
		(pad "28" smd rect
			(at 0.249936 -2.237486 180)
			(size 0.254 0.381)
			(layers "F.Cu" "F.Mask" "F.Paste")
			(net "P12V_AUX")
		)
		(pad "29" smd rect
			(at -0.249936 -2.237486 180)
			(size 0.254 0.381)
			(layers "F.Cu" "F.Mask" "F.Paste")
			(net "P12V_AUX")
		)
		(pad "30" smd rect
			(at -0.750062 -2.237486 180)
			(size 0.254 0.381)
			(layers "F.Cu" "F.Mask" "F.Paste")
			(net "P12V_AUX")
		)
		(pad "31" smd rect
			(at -1.249934 -2.237486 180)
			(size 0.254 0.381)
			(layers "F.Cu" "F.Mask" "F.Paste")
			(net "P12V_AUX")
		)
		(pad "32" smd rect
			(at -1.75006 -2.250186 180)
			(size 0.254 0.3556)
			(layers "F.Cu" "F.Mask" "F.Paste")
			(net "P12V_AUX")
		)
		(pad "33" smd rect
			(at 0 0 180)
			(size 3.4036 3.4036)
			(layers "F.Cu" "F.Mask" "F.Paste")
			(net "P12V_PSU")
		)
		(zone
			(layer "F.Cu")
			(hatch none 0.5)
			(connect_pads
				(clearance 0)
			)
			(min_thickness 0.25)
			(keepout
				(tracks not_allowed)
				(vias allowed)
				(pads allowed)
				(copperpour not_allowed)
				(footprints allowed)
			)
			(placement
				(enabled no)
				(sheetname "")
			)
			(fill
				(thermal_gap 0.5)
				(thermal_bridge_width 0.5)
				(island_removal_mode 0)
			)
			(polygon
				(pts
					(xy 229.518972 -403.479) (xy 229.787958 -403.479) (xy 229.787958 -400.167602) (xy 233.293158 -400.167602)
					(xy 233.293158 -402.428202) (xy 233.536744 -402.428202) (xy 233.536744 -400.472402) (xy 233.562144 -400.472402)
					(xy 233.562144 -399.898616) (xy 232.988358 -399.898616) (xy 232.988358 -399.924016) (xy 230.092758 -399.924016)
					(xy 230.092758 -399.898616) (xy 229.518972 -399.898616) (xy 229.518972 -400.472402) (xy 229.544372 -400.472402)
					(xy 229.544372 -403.368002) (xy 229.518972 -403.368002)
				)
			)
		)
	)
)
